(kicad_pcb
	(version 20260206)
	(generator "pcbnew")
	(generator_version "10.0")
	(general
		(thickness 1.6)
		(legacy_teardrops no)
	)
	(paper "A4")
	(title_block
		(title "v2-tray-backplane — ms_tbp_v2.brd")
		(comment 1 "Open CloudServer (Microsoft) / footprints 84-94 of 164")
	)
	(layers
		(0 "F.Cu" signal "TOP")
		(4 "In1.Cu" signal "LYR2")
		(6 "In2.Cu" signal "LYR3")
		(8 "In3.Cu" signal "LYR4")
		(10 "In4.Cu" signal "LYR5")
		(12 "In5.Cu" signal "LYR6")
		(14 "In6.Cu" signal "LYR7")
		(2 "B.Cu" signal "BOTTOM")
		(9 "F.Adhes" user "F.Adhesive")
		(11 "B.Adhes" user "B.Adhesive")
		(13 "F.Paste" user "Package Geometry/Pastemask Top")
		(15 "B.Paste" user "Package Geometry/Pastemask Bottom")
		(5 "F.SilkS" user "Ref Des/Silkscreen Top")
		(7 "B.SilkS" user "Ref Des/Silkscreen Bottom")
		(1 "F.Mask" user "Board Geometry/Soldermask Top")
		(3 "B.Mask" user "Board Geometry/Soldermask Bottom")
		(17 "Dwgs.User" user "User.Drawings")
		(19 "Cmts.User" user "User.Comments")
		(21 "Eco1.User" user "User.Eco1")
		(23 "Eco2.User" user "User.Eco2")
		(25 "Edge.Cuts" user "Board Geometry/Outline")
		(27 "Margin" user)
		(31 "F.CrtYd" user "Package Geometry/Place Bound Top")
		(29 "B.CrtYd" user "Package Geometry/Place Bound Bottom")
		(35 "F.Fab" user "Ref Des/Assembly Top")
		(33 "B.Fab" user "Ref Des/Assembly Bottom")
	)
	(footprint ""
		(layer "F.Cu")
		(at -136.017 31.6992 90)
		(property "Reference" "C14"
			(at -2.286 -0.0889 90)
			(unlocked yes)
			(layer "F.SilkS")
			(effects
				(font
					(size 0.762 0.5334)
					(thickness 0.1016)
				)
			)
		)
		(property "Value" ""
			(at 0 0 90)
			(layer "F.Fab")
			(effects
				(font
					(size 1.27 1.27)
				)
			)
		)
		(duplicate_pad_numbers_are_jumpers no)
		(fp_line
			(start 0 -0.381)
			(end 0 0.381)
			(stroke
				(width 0.127)
				(type default)
			)
			(layer "F.SilkS")
		)
		(fp_poly
			(pts
				(xy 1.253299 0.656399) (xy -1.2533 0.656399) (xy -1.2533 -0.6564) (xy 1.253299 -0.6564)
			)
			(stroke
				(width 0)
				(type default)
			)
			(fill no)
			(layer "F.CrtYd")
		)
		(fp_line
			(start 0.762 -0.381)
			(end -0.762 -0.381)
			(stroke
				(width 0.1)
				(type default)
			)
			(layer "F.Fab")
		)
		(fp_line
			(start -0.762 -0.381)
			(end -0.762 0.381)
			(stroke
				(width 0.1)
				(type default)
			)
			(layer "F.Fab")
		)
		(fp_line
			(start 0.762 0.381)
			(end 0.762 -0.381)
			(stroke
				(width 0.1)
				(type default)
			)
			(layer "F.Fab")
		)
		(fp_line
			(start -0.762 0.381)
			(end 0.762 0.381)
			(stroke
				(width 0.1)
				(type default)
			)
			(layer "F.Fab")
		)
		(pad "1" smd rect
			(at -0.6477 0 90)
			(size 0.7112 0.8128)
			(layers "F.Cu" "F.Mask" "F.Paste")
			(net "P12V")
		)
		(pad "2" smd rect
			(at 0.6477 0 270)
			(size 0.7112 0.8128)
			(layers "F.Cu" "F.Mask" "F.Paste")
			(net "GND")
		)
	)
	(footprint ""
		(layer "F.Cu")
		(at -131.8768 31.877 90)
		(property "Reference" "C16"
			(at -2.286 0.0381 90)
			(unlocked yes)
			(layer "F.SilkS")
			(effects
				(font
					(size 0.762 0.5334)
					(thickness 0.1016)
				)
			)
		)
		(property "Value" ""
			(at 0 0 90)
			(layer "F.Fab")
			(effects
				(font
					(size 1.27 1.27)
				)
			)
		)
		(duplicate_pad_numbers_are_jumpers no)
		(fp_poly
			(pts
				(xy -0.9993 0.503999) (xy -0.9993 -0.504) (xy 0.999299 -0.504) (xy 0.999299 0.503999)
			)
			(stroke
				(width 0)
				(type default)
			)
			(fill no)
			(layer "F.CrtYd")
		)
		(fp_line
			(start 0.499999 -0.25)
			(end 0.499999 0.249999)
			(stroke
				(width 0.1)
				(type default)
			)
			(layer "F.Fab")
		)
		(fp_line
			(start -0.499999 -0.25)
			(end 0.499999 -0.25)
			(stroke
				(width 0.1)
				(type default)
			)
			(layer "F.Fab")
		)
		(fp_line
			(start 0.499999 0.249999)
			(end -0.499999 0.249999)
			(stroke
				(width 0.1)
				(type default)
			)
			(layer "F.Fab")
		)
		(fp_line
			(start -0.499999 0.249999)
			(end -0.499999 -0.25)
			(stroke
				(width 0.1)
				(type default)
			)
			(layer "F.Fab")
		)
		(pad "1" smd rect
			(at -0.4572 0 180)
			(size 0.508 0.5842)
			(layers "F.Cu" "F.Mask" "F.Paste")
			(net "P12V")
		)
		(pad "2" smd rect
			(at 0.4572 0 180)
			(size 0.508 0.5842)
			(layers "F.Cu" "F.Mask" "F.Paste")
			(net "GND")
		)
	)
	(footprint ""
		(layer "F.Cu")
		(at -55.9308 45.6946)
		(property "Reference" "FS4"
			(at -0.0762 1.0795 0)
			(unlocked yes)
			(layer "F.SilkS")
			(effects
				(font
					(size 0.762 0.5334)
					(thickness 0.1016)
				)
			)
		)
		(property "Value" ""
			(at 0 0 0)
			(layer "F.Fab")
			(effects
				(font
					(size 1.27 1.27)
				)
			)
		)
		(duplicate_pad_numbers_are_jumpers no)
		(fp_poly
			(pts
				(xy -1.002101 0.504) (xy -1.002101 -0.503999) (xy 1.002101 -0.503999) (xy 1.002101 0.504)
			)
			(stroke
				(width 0)
				(type default)
			)
			(fill no)
			(layer "F.CrtYd")
		)
		(fp_line
			(start -0.499999 -0.249999)
			(end -0.499999 0.25)
			(stroke
				(width 0.1)
				(type default)
			)
			(layer "F.Fab")
		)
		(fp_line
			(start -0.499999 0.25)
			(end 0.499999 0.25)
			(stroke
				(width 0.1)
				(type default)
			)
			(layer "F.Fab")
		)
		(fp_line
			(start 0.499999 -0.249999)
			(end -0.499999 -0.249999)
			(stroke
				(width 0.1)
				(type default)
			)
			(layer "F.Fab")
		)
		(fp_line
			(start 0.499999 0.25)
			(end 0.499999 -0.249999)
			(stroke
				(width 0.1)
				(type default)
			)
			(layer "F.Fab")
		)
		(pad "1" smd rect
			(at -0.459999 0 90)
			(size 0.508 0.5842)
			(layers "F.Cu" "F.Mask" "F.Paste")
			(net "UNNAMED_6_FERRITE_I27_B")
		)
		(pad "2" smd rect
			(at 0.459999 0 90)
			(size 0.508 0.5842)
			(layers "F.Cu" "F.Mask" "F.Paste")
			(net "P3V3_B2_QSFP")
		)
	)
	(footprint ""
		(layer "F.Cu")
		(at -80.0862 9.2456 180)
		(property "Reference" "R33"
			(at 3.0988 -0.0635 0)
			(unlocked yes)
			(layer "F.SilkS")
			(effects
				(font
					(size 0.762 0.5334)
					(thickness 0.1016)
				)
			)
		)
		(property "Value" ""
			(at 0 0 180)
			(layer "F.Fab")
			(effects
				(font
					(size 1.27 1.27)
				)
			)
		)
		(duplicate_pad_numbers_are_jumpers no)
		(fp_line
			(start 0 -0.381)
			(end 0 0.381)
			(stroke
				(width 0.127)
				(type default)
			)
			(layer "F.SilkS")
		)
		(fp_poly
			(pts
				(xy 1.255601 0.656399) (xy -1.255601 0.656399) (xy -1.255601 -0.6564) (xy 1.255601 -0.6564)
			)
			(stroke
				(width 0)
				(type default)
			)
			(fill no)
			(layer "F.CrtYd")
		)
		(fp_line
			(start 0.800001 0.399999)
			(end 0.800001 -0.399999)
			(stroke
				(width 0.1)
				(type default)
			)
			(layer "F.Fab")
		)
		(fp_line
			(start 0.800001 -0.399999)
			(end -0.800001 -0.399999)
			(stroke
				(width 0.1)
				(type default)
			)
			(layer "F.Fab")
		)
		(fp_line
			(start -0.800001 0.399999)
			(end 0.800001 0.399999)
			(stroke
				(width 0.1)
				(type default)
			)
			(layer "F.Fab")
		)
		(fp_line
			(start -0.800001 -0.399999)
			(end -0.800001 0.399999)
			(stroke
				(width 0.1)
				(type default)
			)
			(layer "F.Fab")
		)
		(pad "1" smd rect
			(at -0.650001 0 180)
			(size 0.7112 0.8128)
			(layers "F.Cu" "F.Mask" "F.Paste")
			(net "SKU_B2_ID1")
		)
		(pad "2" smd rect
			(at 0.650001 0)
			(size 0.7112 0.8128)
			(layers "F.Cu" "F.Mask" "F.Paste")
			(net "GND")
		)
	)
	(footprint ""
		(layer "F.Cu")
		(at -46.393001 11.519002 90)
		(property "Reference" "FB7"
			(at 0.513182 -2.374999 0)
			(unlocked yes)
			(layer "F.SilkS")
			(effects
				(font
					(size 0.762 0.5334)
					(thickness 0.1016)
				)
				(justify left)
			)
		)
		(property "Value" ""
			(at 0 0 90)
			(layer "F.Fab")
			(effects
				(font
					(size 1.27 1.27)
				)
			)
		)
		(duplicate_pad_numbers_are_jumpers no)
		(fp_poly
			(pts
				(xy -1.016 0.508) (xy -1.016 -0.508) (xy 1.016 -0.508) (xy 1.016 0.508)
			)
			(stroke
				(width 0)
				(type default)
			)
			(fill no)
			(layer "F.CrtYd")
		)
		(fp_line
			(start 0.508 -0.254)
			(end 0.508 0.254)
			(stroke
				(width 0.1)
				(type default)
			)
			(layer "F.Fab")
		)
		(fp_line
			(start -0.508 -0.254)
			(end 0.508 -0.254)
			(stroke
				(width 0.1)
				(type default)
			)
			(layer "F.Fab")
		)
		(fp_line
			(start 0.508 0.254)
			(end -0.508 0.254)
			(stroke
				(width 0.1)
				(type default)
			)
			(layer "F.Fab")
		)
		(fp_line
			(start -0.508 0.254)
			(end -0.508 -0.254)
			(stroke
				(width 0.1)
				(type default)
			)
			(layer "F.Fab")
		)
		(pad "1" smd rect
			(at -0.4572 0 180)
			(size 0.508 0.5842)
			(layers "F.Cu" "F.Mask" "F.Paste")
			(net "P3V3_40G_B2_VCC1")
		)
		(pad "2" smd rect
			(at 0.4572 0 180)
			(size 0.508 0.5842)
			(layers "F.Cu" "F.Mask" "F.Paste")
			(net "UNNAMED_8_FERRITE_I47_B")
		)
	)
	(footprint ""
		(layer "F.Cu")
		(at -331.47 20.2438 180)
		(property "Reference" "R7"
			(at -1.9812 0.05842 0)
			(unlocked yes)
			(layer "F.SilkS")
			(effects
				(font
					(size 0.762 0.5334)
					(thickness 0.1016)
				)
			)
		)
		(property "Value" ""
			(at 0 0 180)
			(layer "F.Fab")
			(effects
				(font
					(size 1.27 1.27)
				)
			)
		)
		(duplicate_pad_numbers_are_jumpers no)
		(fp_line
			(start 0 -0.381)
			(end 0 0.381)
			(stroke
				(width 0.127)
				(type default)
			)
			(layer "F.SilkS")
		)
		(fp_poly
			(pts
				(xy 1.255601 0.656399) (xy -1.255601 0.656399) (xy -1.255601 -0.6564) (xy 1.255601 -0.6564)
			)
			(stroke
				(width 0)
				(type default)
			)
			(fill no)
			(layer "F.CrtYd")
		)
		(fp_line
			(start 0.800001 0.399999)
			(end 0.800001 -0.399999)
			(stroke
				(width 0.1)
				(type default)
			)
			(layer "F.Fab")
		)
		(fp_line
			(start 0.800001 -0.399999)
			(end -0.800001 -0.399999)
			(stroke
				(width 0.1)
				(type default)
			)
			(layer "F.Fab")
		)
		(fp_line
			(start -0.800001 0.399999)
			(end 0.800001 0.399999)
			(stroke
				(width 0.1)
				(type default)
			)
			(layer "F.Fab")
		)
		(fp_line
			(start -0.800001 -0.399999)
			(end -0.800001 0.399999)
			(stroke
				(width 0.1)
				(type default)
			)
			(layer "F.Fab")
		)
		(pad "1" smd rect
			(at -0.650001 0 180)
			(size 0.7112 0.8128)
			(layers "F.Cu" "F.Mask" "F.Paste")
			(net "SKU_B1_ID2")
		)
		(pad "2" smd rect
			(at 0.650001 0)
			(size 0.7112 0.8128)
			(layers "F.Cu" "F.Mask" "F.Paste")
			(net "GND")
		)
	)
	(footprint ""
		(layer "F.Cu")
		(at -80.0862 0.381 180)
		(property "Reference" "R57"
			(at 3.07086 -0.03048 0)
			(unlocked yes)
			(layer "F.SilkS")
			(effects
				(font
					(size 0.762 0.5334)
					(thickness 0.1016)
				)
			)
		)
		(property "Value" ""
			(at 0 0 180)
			(layer "F.Fab")
			(effects
				(font
					(size 1.27 1.27)
				)
			)
		)
		(duplicate_pad_numbers_are_jumpers no)
		(fp_line
			(start 0 -0.381)
			(end 0 0.381)
			(stroke
				(width 0.127)
				(type default)
			)
			(layer "F.SilkS")
		)
		(fp_poly
			(pts
				(xy 1.255601 0.6564) (xy -1.255601 0.6564) (xy -1.255601 -0.6564) (xy 1.255601 -0.6564)
			)
			(stroke
				(width 0)
				(type default)
			)
			(fill no)
			(layer "F.CrtYd")
		)
		(fp_line
			(start 0.800001 0.399999)
			(end 0.800001 -0.399999)
			(stroke
				(width 0.1)
				(type default)
			)
			(layer "F.Fab")
		)
		(fp_line
			(start 0.800001 -0.399999)
			(end -0.800001 -0.399999)
			(stroke
				(width 0.1)
				(type default)
			)
			(layer "F.Fab")
		)
		(fp_line
			(start -0.800001 0.399999)
			(end 0.800001 0.399999)
			(stroke
				(width 0.1)
				(type default)
			)
			(layer "F.Fab")
		)
		(fp_line
			(start -0.800001 -0.399999)
			(end -0.800001 0.399999)
			(stroke
				(width 0.1)
				(type default)
			)
			(layer "F.Fab")
		)
		(pad "1" smd rect
			(at -0.650001 0 180)
			(size 0.7112 0.8128)
			(layers "F.Cu" "F.Mask" "F.Paste")
			(net "ETH10G_B2_MOD_ABS")
		)
		(pad "2" smd rect
			(at 0.650001 0)
			(size 0.7112 0.8128)
			(layers "F.Cu" "F.Mask" "F.Paste")
			(net "P3V3_B2_QSFP")
		)
	)
	(footprint ""
		(layer "F.Cu")
		(at -279.610401 44.488202)
		(property "Reference" "C6"
			(at 2.242401 -0.000102 0)
			(unlocked yes)
			(layer "F.SilkS")
			(effects
				(font
					(size 0.762 0.5334)
					(thickness 0.1016)
				)
			)
		)
		(property "Value" ""
			(at 0 0 0)
			(layer "F.Fab")
			(effects
				(font
					(size 1.27 1.27)
				)
			)
		)
		(duplicate_pad_numbers_are_jumpers no)
		(fp_poly
			(pts
				(xy -0.999299 0.503999) (xy -0.999299 -0.504) (xy 0.9993 -0.504) (xy 0.9993 0.503999)
			)
			(stroke
				(width 0)
				(type default)
			)
			(fill no)
			(layer "F.CrtYd")
		)
		(fp_line
			(start -0.499999 -0.25)
			(end 0.499999 -0.25)
			(stroke
				(width 0.1)
				(type default)
			)
			(layer "F.Fab")
		)
		(fp_line
			(start -0.499999 0.249999)
			(end -0.499999 -0.25)
			(stroke
				(width 0.1)
				(type default)
			)
			(layer "F.Fab")
		)
		(fp_line
			(start 0.499999 -0.25)
			(end 0.499999 0.249999)
			(stroke
				(width 0.1)
				(type default)
			)
			(layer "F.Fab")
		)
		(fp_line
			(start 0.499999 0.249999)
			(end -0.499999 0.249999)
			(stroke
				(width 0.1)
				(type default)
			)
			(layer "F.Fab")
		)
		(pad "1" smd rect
			(at -0.4572 0 90)
			(size 0.508 0.5842)
			(layers "F.Cu" "F.Mask" "F.Paste")
			(net "P3V3_10G_B1_VCCT")
		)
		(pad "2" smd rect
			(at 0.4572 0 90)
			(size 0.508 0.5842)
			(layers "F.Cu" "F.Mask" "F.Paste")
			(net "GND")
		)
	)
	(footprint ""
		(layer "F.Cu")
		(at -63.563401 44.488202 180)
		(property "Reference" "C12"
			(at 2.603599 -0.126898 0)
			(unlocked yes)
			(layer "F.SilkS")
			(effects
				(font
					(size 0.762 0.5334)
					(thickness 0.1016)
				)
			)
		)
		(property "Value" ""
			(at 0 0 180)
			(layer "F.Fab")
			(effects
				(font
					(size 1.27 1.27)
				)
			)
		)
		(duplicate_pad_numbers_are_jumpers no)
		(fp_poly
			(pts
				(xy -0.9993 0.504) (xy -0.9993 -0.503999) (xy 0.999299 -0.503999) (xy 0.999299 0.504)
			)
			(stroke
				(width 0)
				(type default)
			)
			(fill no)
			(layer "F.CrtYd")
		)
		(fp_line
			(start 0.499999 0.25)
			(end -0.499999 0.25)
			(stroke
				(width 0.1)
				(type default)
			)
			(layer "F.Fab")
		)
		(fp_line
			(start 0.499999 -0.249999)
			(end 0.499999 0.25)
			(stroke
				(width 0.1)
				(type default)
			)
			(layer "F.Fab")
		)
		(fp_line
			(start -0.499999 0.25)
			(end -0.499999 -0.249999)
			(stroke
				(width 0.1)
				(type default)
			)
			(layer "F.Fab")
		)
		(fp_line
			(start -0.499999 -0.249999)
			(end 0.499999 -0.249999)
			(stroke
				(width 0.1)
				(type default)
			)
			(layer "F.Fab")
		)
		(pad "1" smd rect
			(at -0.4572 0 270)
			(size 0.508 0.5842)
			(layers "F.Cu" "F.Mask" "F.Paste")
			(net "P3V3_10G_B2_VCCR")
		)
		(pad "2" smd rect
			(at 0.4572 0 270)
			(size 0.508 0.5842)
			(layers "F.Cu" "F.Mask" "F.Paste")
			(net "GND")
		)
	)
	(footprint ""
		(layer "F.Cu")
		(at -110.8456 20.2184 180)
		(property "Reference" "R35"
			(at -3.2766 0.1143 0)
			(unlocked yes)
			(layer "F.SilkS")
			(effects
				(font
					(size 0.762 0.5334)
					(thickness 0.1016)
				)
			)
		)
		(property "Value" ""
			(at 0 0 180)
			(layer "F.Fab")
			(effects
				(font
					(size 1.27 1.27)
				)
			)
		)
		(duplicate_pad_numbers_are_jumpers no)
		(fp_line
			(start 0 -0.381)
			(end 0 0.381)
			(stroke
				(width 0.127)
				(type default)
			)
			(layer "F.SilkS")
		)
		(fp_poly
			(pts
				(xy 1.255601 0.656399) (xy -1.255601 0.656399) (xy -1.255601 -0.6564) (xy 1.255601 -0.6564)
			)
			(stroke
				(width 0)
				(type default)
			)
			(fill no)
			(layer "F.CrtYd")
		)
		(fp_line
			(start 0.800001 0.399999)
			(end 0.800001 -0.399999)
			(stroke
				(width 0.1)
				(type default)
			)
			(layer "F.Fab")
		)
		(fp_line
			(start 0.800001 -0.399999)
			(end -0.800001 -0.399999)
			(stroke
				(width 0.1)
				(type default)
			)
			(layer "F.Fab")
		)
		(fp_line
			(start -0.800001 0.399999)
			(end 0.800001 0.399999)
			(stroke
				(width 0.1)
				(type default)
			)
			(layer "F.Fab")
		)
		(fp_line
			(start -0.800001 -0.399999)
			(end -0.800001 0.399999)
			(stroke
				(width 0.1)
				(type default)
			)
			(layer "F.Fab")
		)
		(pad "1" smd rect
			(at -0.650001 0 180)
			(size 0.7112 0.8128)
			(layers "F.Cu" "F.Mask" "F.Paste")
			(net "SKU_B2_ID2")
		)
		(pad "2" smd rect
			(at 0.650001 0)
			(size 0.7112 0.8128)
			(layers "F.Cu" "F.Mask" "F.Paste")
			(net "GND")
		)
	)
	(footprint ""
		(layer "F.Cu")
		(at -300.9392 0 180)
		(property "Reference" "R29"
			(at 3.3782 -0.0381 0)
			(unlocked yes)
			(layer "F.SilkS")
			(effects
				(font
					(size 0.762 0.5334)
					(thickness 0.1016)
				)
			)
		)
		(property "Value" ""
			(at 0 0 180)
			(layer "F.Fab")
			(effects
				(font
					(size 1.27 1.27)
				)
			)
		)
		(duplicate_pad_numbers_are_jumpers no)
		(fp_line
			(start 0 -0.381)
			(end 0 0.381)
			(stroke
				(width 0.127)
				(type default)
			)
			(layer "F.SilkS")
		)
		(fp_poly
			(pts
				(xy 1.255601 0.6564) (xy -1.255601 0.6564) (xy -1.255601 -0.6564) (xy 1.255601 -0.6564)
			)
			(stroke
				(width 0)
				(type default)
			)
			(fill no)
			(layer "F.CrtYd")
		)
		(fp_line
			(start 0.800001 0.399999)
			(end 0.800001 -0.399999)
			(stroke
				(width 0.1)
				(type default)
			)
			(layer "F.Fab")
		)
		(fp_line
			(start 0.800001 -0.399999)
			(end -0.800001 -0.399999)
			(stroke
				(width 0.1)
				(type default)
			)
			(layer "F.Fab")
		)
		(fp_line
			(start -0.800001 0.399999)
			(end 0.800001 0.399999)
			(stroke
				(width 0.1)
				(type default)
			)
			(layer "F.Fab")
		)
		(fp_line
			(start -0.800001 -0.399999)
			(end -0.800001 0.399999)
			(stroke
				(width 0.1)
				(type default)
			)
			(layer "F.Fab")
		)
		(pad "1" smd rect
			(at -0.650001 0 180)
			(size 0.7112 0.8128)
			(layers "F.Cu" "F.Mask" "F.Paste")
			(net "ETH10G_B1_MOD_ABS")
		)
		(pad "2" smd rect
			(at 0.650001 0)
			(size 0.7112 0.8128)
			(layers "F.Cu" "F.Mask" "F.Paste")
			(net "P3V3_B1_QSFP")
		)
	)
)
